# BASEBOARD_FAB2 (Tioga Pass) — schematic netlist excerpt (pin names and nets, part order shuffled) for the footprints in the layout excerpt that follows; sources: Cadence DE-HDL packaged netlist, KiCad conversion of Wiwynn_Tioga_Pass_MB.brd

J9A2  CONN14_H54902001  CONN  pkg PIP  page 155
  IO1  = LED_POSTCODE_0_R
  IO2  = LED_POSTCODE_1_R
  IO3  = LED_POSTCODE_2_R
  IO4  = LED_POSTCODE_3_R
  IO5  = LED_POSTCODE_4_R
  IO6  = LED_POSTCODE_5_R
  IO7  = LED_POSTCODE_6_R
  IO8  = LED_POSTCODE_7_R
  IO9  = SPA_MID_DBG1_TX
  IO10  = SPA_5V_SIN_SW
  IO11  = FM_DEBUG_RST_BTN_N
  IO12  = FM_UART_SWITCH_N
  IO13  = GND
  IO14  = P5V_STBY_DGB_FS

(kicad_pcb
	(version 20260206)
	(generator "pcbnew")
	(generator_version "10.0")
	(general
		(thickness 1.6)
		(legacy_teardrops no)
	)
	(paper "A4")
	(title_block
		(title "Wiwynn_Tioga_Pass_MB.brd")
		(comment 1 "Tioga Pass / footprint 860 of 4770 (J9A2), pads 1-14 of 14")
	)
	(layers
		(0 "F.Cu" signal "TOP")
		(4 "In1.Cu" signal "L2GND")
		(6 "In2.Cu" signal "L3")
		(8 "In3.Cu" signal "L4GND")
		(10 "In4.Cu" signal "L5")
		(12 "In5.Cu" signal "L6GND")
		(14 "In6.Cu" signal "L7VCC")
		(16 "In7.Cu" signal "L8VCC")
		(18 "In8.Cu" signal "L9GND")
		(20 "In9.Cu" signal "L10")
		(22 "In10.Cu" signal "L11GND")
		(24 "In11.Cu" signal "L12")
		(26 "In12.Cu" signal "L13GND")
		(2 "B.Cu" signal "BOTTOM")
		(9 "F.Adhes" user "F.Adhesive")
		(11 "B.Adhes" user "B.Adhesive")
		(13 "F.Paste" user "Package Geometry/Pastemask Top")
		(15 "B.Paste" user "Package Geometry/Pastemask Bottom")
		(5 "F.SilkS" user "Ref Des/Silkscreen Top")
		(7 "B.SilkS" user "Ref Des/Silkscreen Bottom")
		(1 "F.Mask" user "Board Geometry/Soldermask Top")
		(3 "B.Mask" user "Board Geometry/Soldermask Bottom")
		(17 "Dwgs.User" user "User.Drawings")
		(19 "Cmts.User" user "User.Comments")
		(21 "Eco1.User" user "User.Eco1")
		(23 "Eco2.User" user "User.Eco2")
		(25 "Edge.Cuts" user "Board Geometry/Outline")
		(27 "Margin" user)
		(31 "F.CrtYd" user "Package Geometry/Place Bound Top")
		(29 "B.CrtYd" user "Package Geometry/Place Bound Bottom")
		(35 "F.Fab" user "Ref Des/Assembly Top")
		(33 "B.Fab" user "Ref Des/Assembly Bottom")
	)
	(footprint ""
		(layer "F.Cu")
		(at 496.000024 -141.849856 180)
		(property "Reference" "J9A2"
			(at -0.48768 -1.76403 0)
			(unlocked yes)
			(layer "B.SilkS")
			(effects
				(font
					(size 0.7874 0.5842)
					(thickness 0.1524)
				)
				(justify left mirror)
			)
		)
		(property "Value" ""
			(at 0 0 180)
			(layer "F.Fab")
			(effects
				(font
					(size 1.27 1.27)
				)
			)
		)
		(duplicate_pad_numbers_are_jumpers no)
		(pad "1" thru_hole rect
			(at 0 0 180)
			(size 1.397 1.397)
			(drill 1.016)
			(layers "*.Cu" "*.Mask")
			(remove_unused_layers no)
			(net "LED_POSTCODE_0_R")
			(clearance 0.127)
			(thermal_gap 0.127)
			(padstack
				(mode front_inner_back)
				(layer "Inner"
					(shape circle)
					(size 1.397 1.397)
					(clearance 0.127)
				)
				(layer "B.Cu"
					(shape rect)
					(size 1.397 1.397)
					(clearance 0.127)
				)
			)
		)
		(pad "2" thru_hole circle
			(at 1.999996 0 180)
			(size 1.397 1.397)
			(drill 1.016)
			(layers "*.Cu" "*.Mask")
			(remove_unused_layers no)
			(net "LED_POSTCODE_1_R")
			(clearance 0.127)
			(thermal_gap 0.127)
		)
		(pad "3" thru_hole circle
			(at 0 1.999996 180)
			(size 1.397 1.397)
			(drill 1.016)
			(layers "*.Cu" "*.Mask")
			(remove_unused_layers no)
			(net "LED_POSTCODE_2_R")
			(clearance 0.127)
			(thermal_gap 0.127)
		)
		(pad "4" thru_hole circle
			(at 1.999996 1.999996 180)
			(size 1.397 1.397)
			(drill 1.016)
			(layers "*.Cu" "*.Mask")
			(remove_unused_layers no)
			(net "LED_POSTCODE_3_R")
			(clearance 0.127)
			(thermal_gap 0.127)
		)
		(pad "5" thru_hole circle
			(at 0 3.999992 180)
			(size 1.397 1.397)
			(drill 1.016)
			(layers "*.Cu" "*.Mask")
			(remove_unused_layers no)
			(net "LED_POSTCODE_4_R")
			(clearance 0.127)
			(thermal_gap 0.127)
		)
		(pad "6" thru_hole circle
			(at 1.999996 3.999992 180)
			(size 1.397 1.397)
			(drill 1.016)
			(layers "*.Cu" "*.Mask")
			(remove_unused_layers no)
			(net "LED_POSTCODE_5_R")
			(clearance 0.127)
			(thermal_gap 0.127)
		)
		(pad "7" thru_hole circle
			(at 0 5.999988 180)
			(size 1.397 1.397)
			(drill 1.016)
			(layers "*.Cu" "*.Mask")
			(remove_unused_layers no)
			(net "LED_POSTCODE_6_R")
			(clearance 0.127)
			(thermal_gap 0.127)
		)
		(pad "8" thru_hole circle
			(at 1.999996 5.999988 180)
			(size 1.397 1.397)
			(drill 1.016)
			(layers "*.Cu" "*.Mask")
			(remove_unused_layers no)
			(net "LED_POSTCODE_7_R")
			(clearance 0.127)
			(thermal_gap 0.127)
		)
		(pad "9" thru_hole circle
			(at 0 7.999984 180)
			(size 1.397 1.397)
			(drill 1.016)
			(layers "*.Cu" "*.Mask")
			(remove_unused_layers no)
			(net "SPA_MID_DBG1_TX")
			(clearance 0.127)
			(thermal_gap 0.127)
		)
		(pad "10" thru_hole circle
			(at 1.999996 7.999984 180)
			(size 1.397 1.397)
			(drill 1.016)
			(layers "*.Cu" "*.Mask")
			(remove_unused_layers no)
			(net "SPA_5V_SIN_SW")
			(clearance 0.127)
			(thermal_gap 0.127)
		)
		(pad "11" thru_hole circle
			(at 0 9.99998 180)
			(size 1.397 1.397)
			(drill 1.016)
			(layers "*.Cu" "*.Mask")
			(remove_unused_layers no)
			(net "FM_DEBUG_RST_BTN_N")
			(clearance 0.127)
			(thermal_gap 0.127)
		)
		(pad "12" thru_hole circle
			(at 1.999996 9.99998 180)
			(size 1.397 1.397)
			(drill 1.016)
			(layers "*.Cu" "*.Mask")
			(remove_unused_layers no)
			(net "FM_UART_SWITCH_N")
			(clearance 0.127)
			(thermal_gap 0.127)
		)
		(pad "13" thru_hole circle
			(at 0 11.999976 180)
			(size 1.397 1.397)
			(drill 1.016)
			(layers "*.Cu" "*.Mask")
			(remove_unused_layers no)
			(net "GND")
			(clearance 0.127)
			(thermal_gap 0.127)
		)
		(pad "14" thru_hole circle
			(at 1.999996 11.999976 180)
			(size 1.397 1.397)
			(drill 1.016)
			(layers "*.Cu" "*.Mask")
			(remove_unused_layers no)
			(net "P5V_STBY_DGB_FS")
			(clearance 0.127)
			(thermal_gap 0.127)
		)
	)
)
